(kicad_pcb
	(version 20260206)
	(generator "pcbnew")
	(generator_version "10.0")
	(general
		(thickness 1.6)
		(legacy_teardrops no)
	)
	(paper "A4")
	(title_block
		(title "12092022_DA0F0TFB6D0_F0T_FAN_BOARD_MP5048_D_brd_v02_OCP.brd")
		(comment 1 "Grand Teton / footprints 772-776 of 924")
	)
	(layers
		(0 "F.Cu" signal "TOP")
		(4 "In1.Cu" signal "GND")
		(6 "In2.Cu" signal "IN1")
		(8 "In3.Cu" signal "IN2")
		(10 "In4.Cu" signal "GND1")
		(2 "B.Cu" signal "BOTTOM")
		(9 "F.Adhes" user "F.Adhesive")
		(11 "B.Adhes" user "B.Adhesive")
		(13 "F.Paste" user "Package Geometry/Pastemask Top")
		(15 "B.Paste" user "Package Geometry/Pastemask Bottom")
		(5 "F.SilkS" user "Ref Des/Silkscreen Top")
		(7 "B.SilkS" user "Ref Des/Silkscreen Bottom")
		(1 "F.Mask" user "Board Geometry/Soldermask Top")
		(3 "B.Mask" user "Board Geometry/Soldermask Bottom")
		(17 "Dwgs.User" user "User.Drawings")
		(19 "Cmts.User" user "User.Comments")
		(21 "Eco1.User" user "User.Eco1")
		(23 "Eco2.User" user "User.Eco2")
		(25 "Edge.Cuts" user "Board Geometry/Outline")
		(27 "Margin" user)
		(31 "F.CrtYd" user "Package Geometry/Place Bound Top")
		(29 "B.CrtYd" user "Package Geometry/Place Bound Bottom")
		(35 "F.Fab" user "Ref Des/Assembly Top")
		(33 "B.Fab" user "Ref Des/Assembly Bottom")
	)
	(footprint ""
		(layer "B.Cu")
		(at 14.774418 -64.192912 90)
		(property "Reference" "PD15"
			(at -5.518912 3.867912 270)
			(unlocked yes)
			(layer "B.SilkS")
			(effects
				(font
					(size 0.7874 0.5842)
					(thickness 0.1524)
				)
				(justify left mirror)
			)
		)
		(property "Value" ""
			(at 0 0 90)
			(layer "B.Fab")
			(effects
				(font
					(size 1.27 1.27)
				)
				(justify mirror)
			)
		)
		(duplicate_pad_numbers_are_jumpers no)
		(fp_line
			(start 4.647184 -3.109976)
			(end 4.647184 3.109976)
			(stroke
				(width 0.1524)
				(type default)
			)
			(layer "B.SilkS")
		)
		(fp_line
			(start -5.536184 -3.109976)
			(end 4.647184 -3.109976)
			(stroke
				(width 0.1524)
				(type default)
			)
			(layer "B.SilkS")
		)
		(fp_line
			(start -0.762 -1.143)
			(end -0.762 0.889)
			(stroke
				(width 0.1524)
				(type default)
			)
			(layer "B.SilkS")
		)
		(fp_line
			(start 0.635 -0.889)
			(end 0.635 0.635)
			(stroke
				(width 0.1524)
				(type default)
			)
			(layer "B.SilkS")
		)
		(fp_line
			(start 1.397 -0.127)
			(end 0.635 -0.127)
			(stroke
				(width 0.1524)
				(type default)
			)
			(layer "B.SilkS")
		)
		(fp_line
			(start -0.635 -0.127)
			(end 0.635 -0.889)
			(stroke
				(width 0.1524)
				(type default)
			)
			(layer "B.SilkS")
		)
		(fp_line
			(start -0.635 -0.127)
			(end -1.397 -0.127)
			(stroke
				(width 0.1524)
				(type default)
			)
			(layer "B.SilkS")
		)
		(fp_line
			(start 0.635 0.635)
			(end -0.635 -0.127)
			(stroke
				(width 0.1524)
				(type default)
			)
			(layer "B.SilkS")
		)
		(fp_line
			(start 4.647184 3.109976)
			(end -5.536184 3.109976)
			(stroke
				(width 0.1524)
				(type default)
			)
			(layer "B.SilkS")
		)
		(fp_line
			(start -5.536184 3.109976)
			(end -5.536184 -3.109976)
			(stroke
				(width 0.1524)
				(type default)
			)
			(layer "B.SilkS")
		)
		(fp_poly
			(pts
				(xy -5.5118 -3.0988) (xy -5.5118 3.1496) (xy -4.572 3.1496) (xy -4.572 -3.0988)
			)
			(stroke
				(width 0)
				(type default)
			)
			(fill yes)
			(layer "B.SilkS")
		)
		(fp_line
			(start 3.554984 -3.109976)
			(end 3.554984 3.109976)
			(stroke
				(width 0.1)
				(type default)
			)
			(layer "B.Fab")
		)
		(fp_line
			(start -3.554984 -3.109976)
			(end 3.554984 -3.109976)
			(stroke
				(width 0.1)
				(type default)
			)
			(layer "B.Fab")
		)
		(fp_line
			(start 3.554984 3.109976)
			(end -3.554984 3.109976)
			(stroke
				(width 0.1)
				(type default)
			)
			(layer "B.Fab")
		)
		(fp_line
			(start -3.554984 3.109976)
			(end -3.554984 -3.109976)
			(stroke
				(width 0.1)
				(type default)
			)
			(layer "B.Fab")
		)
		(fp_text user "-"
			(at -5.334 -0.34925 90)
			(unlocked yes)
			(layer "B.SilkS")
			(effects
				(font
					(size 1.905 1.4224)
					(thickness 0.1524)
				)
				(justify left mirror)
			)
		)
		(fp_text user "+"
			(at 6.1214 -0.32385 90)
			(unlocked yes)
			(layer "B.SilkS")
			(effects
				(font
					(size 1.905 1.4224)
					(thickness 0.1524)
				)
				(justify left mirror)
			)
		)
		(fp_text user "-"
			(at -5.334 -0.34925 90)
			(unlocked yes)
			(layer "B.Fab")
			(effects
				(font
					(size 1.905 1.4224)
					(thickness 0.1524)
				)
				(justify left mirror)
			)
		)
		(fp_text user "+"
			(at 6.1214 -0.32385 90)
			(unlocked yes)
			(layer "B.Fab")
			(effects
				(font
					(size 1.905 1.4224)
					(thickness 0.1524)
				)
				(justify left mirror)
			)
		)
		(pad "A" smd rect
			(at 3.299968 0 270)
			(size 2.413 3.302)
			(layers "B.Cu" "B.Mask" "B.Paste")
			(net "GND")
		)
		(pad "C" smd rect
			(at -3.299968 0 270)
			(size 2.413 3.302)
			(layers "B.Cu" "B.Mask" "B.Paste")
			(net "P52V_HSC")
		)
	)
	(footprint ""
		(layer "B.Cu")
		(at 17.033494 -255.778 -90)
		(property "Reference" "U398"
			(at 1.524 -2.878836 270)
			(unlocked yes)
			(layer "B.SilkS")
			(effects
				(font
					(size 0.7874 0.5842)
					(thickness 0.1524)
				)
				(justify left mirror)
			)
		)
		(property "Value" ""
			(at 0 0 90)
			(layer "B.Fab")
			(effects
				(font
					(size 1.27 1.27)
				)
				(justify mirror)
			)
		)
		(duplicate_pad_numbers_are_jumpers no)
		(fp_line
			(start -1.3462 1.1938)
			(end -1.3462 -1.1938)
			(stroke
				(width 0.1524)
				(type default)
			)
			(layer "B.SilkS")
		)
		(fp_line
			(start 1.3462 1.1938)
			(end -1.3462 1.1938)
			(stroke
				(width 0.1524)
				(type default)
			)
			(layer "B.SilkS")
		)
		(fp_line
			(start -1.3462 -1.1938)
			(end 1.3462 -1.1938)
			(stroke
				(width 0.1524)
				(type default)
			)
			(layer "B.SilkS")
		)
		(fp_line
			(start 1.3462 -1.1938)
			(end 1.3462 1.1684)
			(stroke
				(width 0.1524)
				(type default)
			)
			(layer "B.SilkS")
		)
		(fp_poly
			(pts
				(xy 1.447038 -0.760476) (xy 2.052066 -0.457962) (xy 2.052066 -1.06299)
			)
			(stroke
				(width 0)
				(type default)
			)
			(fill yes)
			(layer "B.SilkS")
		)
		(fp_line
			(start -0.674878 1.124966)
			(end -0.674878 -1.124966)
			(stroke
				(width 0.1)
				(type default)
			)
			(layer "B.Fab")
		)
		(fp_line
			(start 0.674878 1.124966)
			(end -0.674878 1.124966)
			(stroke
				(width 0.1)
				(type default)
			)
			(layer "B.Fab")
		)
		(fp_line
			(start -0.674878 -1.124966)
			(end 0.674878 -1.124966)
			(stroke
				(width 0.1)
				(type default)
			)
			(layer "B.Fab")
		)
		(fp_line
			(start 0.674878 -1.124966)
			(end 0.674878 1.124966)
			(stroke
				(width 0.1)
				(type default)
			)
			(layer "B.Fab")
		)
		(fp_poly
			(pts
				(xy 1.447038 -0.760476) (xy 2.052066 -0.457962) (xy 2.052066 -1.06299)
			)
			(stroke
				(width 0)
				(type default)
			)
			(fill yes)
			(layer "B.Fab")
		)
		(pad "1" smd rect
			(at 0.899922 -0.750062 90)
			(size 0.6096 0.6096)
			(layers "B.Cu" "B.Mask" "B.Paste")
			(net "NC_U398_P1")
		)
		(pad "2" smd rect
			(at 0.899922 0)
			(size 0.4064 0.6096)
			(layers "B.Cu" "B.Mask" "B.Paste")
			(net "FAN_7_PRSNT_BUF_N")
		)
		(pad "3" smd rect
			(at 0.899922 0.750062 90)
			(size 0.6096 0.6096)
			(layers "B.Cu" "B.Mask" "B.Paste")
			(net "GND")
		)
		(pad "4" smd rect
			(at -0.899922 0.750062 90)
			(size 0.6096 0.6096)
			(layers "B.Cu" "B.Mask" "B.Paste")
			(net "FAN_7_PRESENT")
		)
		(pad "5" smd rect
			(at -0.899922 -0.750062 90)
			(size 0.6096 0.6096)
			(layers "B.Cu" "B.Mask" "B.Paste")
			(net "P3V3_AUX")
		)
	)
	(footprint ""
		(layer "B.Cu")
		(at 17.309846 -269.922244 180)
		(property "Reference" "PC55"
			(at 0 0 0)
			(layer "B.SilkS")
			(hide yes)
			(effects
				(font
					(size 1.27 1.27)
				)
				(justify mirror)
			)
		)
		(property "Value" ""
			(at 0 0 0)
			(layer "B.Fab")
			(effects
				(font
					(size 1.27 1.27)
				)
				(justify mirror)
			)
		)
		(duplicate_pad_numbers_are_jumpers no)
		(fp_line
			(start 1.524 0.762)
			(end 1.524 -0.762)
			(stroke
				(width 0.1524)
				(type default)
			)
			(layer "B.SilkS")
		)
		(fp_line
			(start 1.524 -0.762)
			(end -1.524 -0.762)
			(stroke
				(width 0.1524)
				(type default)
			)
			(layer "B.SilkS")
		)
		(fp_line
			(start -1.524 0.762)
			(end 1.524 0.762)
			(stroke
				(width 0.1524)
				(type default)
			)
			(layer "B.SilkS")
		)
		(fp_line
			(start -1.524 -0.762)
			(end -1.524 0.762)
			(stroke
				(width 0.1524)
				(type default)
			)
			(layer "B.SilkS")
		)
		(fp_line
			(start 1.1049 0.724916)
			(end -1.1049 0.724916)
			(stroke
				(width 0.1)
				(type default)
			)
			(layer "B.Fab")
		)
		(fp_line
			(start 1.1049 -0.724916)
			(end 1.1049 0.724916)
			(stroke
				(width 0.1)
				(type default)
			)
			(layer "B.Fab")
		)
		(fp_line
			(start -1.1049 0.724916)
			(end -1.1049 -0.724916)
			(stroke
				(width 0.1)
				(type default)
			)
			(layer "B.Fab")
		)
		(fp_line
			(start -1.1049 -0.724916)
			(end 1.1049 -0.724916)
			(stroke
				(width 0.1)
				(type default)
			)
			(layer "B.Fab")
		)
		(pad "1" smd rect
			(at 0.889 0 180)
			(size 1.016 1.27)
			(layers "B.Cu" "B.Mask" "B.Paste")
			(net "P52V_FAN_7")
		)
		(pad "2" smd rect
			(at -0.889 0 180)
			(size 1.016 1.27)
			(layers "B.Cu" "B.Mask" "B.Paste")
			(net "GND")
		)
	)
	(footprint ""
		(layer "B.Cu")
		(at 40.894 -127.762 180)
		(property "Reference" "R5431"
			(at 0 0 0)
			(layer "B.SilkS")
			(hide yes)
			(effects
				(font
					(size 1.27 1.27)
				)
				(justify mirror)
			)
		)
		(property "Value" ""
			(at 0 0 0)
			(layer "B.Fab")
			(effects
				(font
					(size 1.27 1.27)
				)
				(justify mirror)
			)
		)
		(duplicate_pad_numbers_are_jumpers no)
		(fp_line
			(start 0.7874 0.4064)
			(end 0.7874 -0.4064)
			(stroke
				(width 0.1524)
				(type default)
			)
			(layer "B.SilkS")
		)
		(fp_line
			(start 0.7874 -0.4064)
			(end -0.7874 -0.4064)
			(stroke
				(width 0.1524)
				(type default)
			)
			(layer "B.SilkS")
		)
		(fp_line
			(start -0.7874 0.4064)
			(end 0.7874 0.4064)
			(stroke
				(width 0.1524)
				(type default)
			)
			(layer "B.SilkS")
		)
		(fp_line
			(start -0.7874 -0.4064)
			(end -0.7874 0.4064)
			(stroke
				(width 0.1524)
				(type default)
			)
			(layer "B.SilkS")
		)
		(fp_line
			(start 0.67945 0.3048)
			(end 0.67945 -0.305054)
			(stroke
				(width 0.1)
				(type default)
			)
			(layer "B.Fab")
		)
		(fp_line
			(start 0.67945 -0.305054)
			(end 0.12065 -0.305054)
			(stroke
				(width 0.1)
				(type default)
			)
			(layer "B.Fab")
		)
		(fp_line
			(start 0.12065 0.3048)
			(end 0.67945 0.3048)
			(stroke
				(width 0.1)
				(type default)
			)
			(layer "B.Fab")
		)
		(fp_line
			(start 0.12065 0.2794)
			(end 0.12065 0.3048)
			(stroke
				(width 0.1)
				(type default)
			)
			(layer "B.Fab")
		)
		(fp_line
			(start 0.12065 -0.2794)
			(end -0.12065 -0.2794)
			(stroke
				(width 0.1)
				(type default)
			)
			(layer "B.Fab")
		)
		(fp_line
			(start 0.12065 -0.305054)
			(end 0.12065 -0.2794)
			(stroke
				(width 0.1)
				(type default)
			)
			(layer "B.Fab")
		)
		(fp_line
			(start -0.120396 0.3048)
			(end -0.120396 0.2794)
			(stroke
				(width 0.1)
				(type default)
			)
			(layer "B.Fab")
		)
		(fp_line
			(start -0.120396 0.2794)
			(end 0.12065 0.2794)
			(stroke
				(width 0.1)
				(type default)
			)
			(layer "B.Fab")
		)
		(fp_line
			(start -0.12065 -0.2794)
			(end -0.12065 -0.3048)
			(stroke
				(width 0.1)
				(type default)
			)
			(layer "B.Fab")
		)
		(fp_line
			(start -0.12065 -0.3048)
			(end -0.67945 -0.3048)
			(stroke
				(width 0.1)
				(type default)
			)
			(layer "B.Fab")
		)
		(fp_line
			(start -0.67945 0.3048)
			(end -0.120396 0.3048)
			(stroke
				(width 0.1)
				(type default)
			)
			(layer "B.Fab")
		)
		(fp_line
			(start -0.67945 -0.3048)
			(end -0.67945 0.3048)
			(stroke
				(width 0.1)
				(type default)
			)
			(layer "B.Fab")
		)
		(pad "1" smd rect
			(at 0.40005 0 180)
			(size 0.4572 0.508)
			(layers "B.Cu" "B.Mask" "B.Paste")
			(net "FAN_2_TACH_OL")
		)
		(pad "2" smd rect
			(at -0.40005 0 180)
			(size 0.4572 0.508)
			(layers "B.Cu" "B.Mask" "B.Paste")
			(net "GND")
		)
	)
	(footprint ""
		(layer "B.Cu")
		(at 16.764 -86.1822 180)
		(property "Reference" "PC43"
			(at 0 0 0)
			(layer "B.SilkS")
			(hide yes)
			(effects
				(font
					(size 1.27 1.27)
				)
				(justify mirror)
			)
		)
		(property "Value" ""
			(at 0 0 0)
			(layer "B.Fab")
			(effects
				(font
					(size 1.27 1.27)
				)
				(justify mirror)
			)
		)
		(duplicate_pad_numbers_are_jumpers no)
		(fp_line
			(start 1.524 0.762)
			(end 1.524 -0.762)
			(stroke
				(width 0.1524)
				(type default)
			)
			(layer "B.SilkS")
		)
		(fp_line
			(start 1.524 -0.762)
			(end -1.524 -0.762)
			(stroke
				(width 0.1524)
				(type default)
			)
			(layer "B.SilkS")
		)
		(fp_line
			(start -1.524 0.762)
			(end 1.524 0.762)
			(stroke
				(width 0.1524)
				(type default)
			)
			(layer "B.SilkS")
		)
		(fp_line
			(start -1.524 -0.762)
			(end -1.524 0.762)
			(stroke
				(width 0.1524)
				(type default)
			)
			(layer "B.SilkS")
		)
		(fp_line
			(start 1.1049 0.724916)
			(end -1.1049 0.724916)
			(stroke
				(width 0.1)
				(type default)
			)
			(layer "B.Fab")
		)
		(fp_line
			(start 1.1049 -0.724916)
			(end 1.1049 0.724916)
			(stroke
				(width 0.1)
				(type default)
			)
			(layer "B.Fab")
		)
		(fp_line
			(start -1.1049 0.724916)
			(end -1.1049 -0.724916)
			(stroke
				(width 0.1)
				(type default)
			)
			(layer "B.Fab")
		)
		(fp_line
			(start -1.1049 -0.724916)
			(end 1.1049 -0.724916)
			(stroke
				(width 0.1)
				(type default)
			)
			(layer "B.Fab")
		)
		(pad "1" smd rect
			(at 0.889 0 180)
			(size 1.016 1.27)
			(layers "B.Cu" "B.Mask" "B.Paste")
			(net "P52V_FAN_5")
		)
		(pad "2" smd rect
			(at -0.889 0 180)
			(size 1.016 1.27)
			(layers "B.Cu" "B.Mask" "B.Paste")
			(net "GND")
		)
	)
)
